# S9S_MB_2U (Grand Teton) — schematic netlist excerpt (pin names and nets, part order shuffled) for the footprints in the layout excerpt that follows; sources: Cadence DE-HDL packaged netlist, KiCad conversion of 03242023_DA0F0TMBIJ0_F0T_Motherboard_J_brd_V01_OCP.brd

PL27  Q_INDUCTOR4P_14  150NH IND  pkg L_TLM117513Q-151QL_11X7-5XA  page 287
  \1\  = SW_PVCCIN_CPU1_SW5
  \2\  = IND_P1_CPL5
  \3\  = IND_P1_CPL4
  \4\  = PVCCIN_CPU1

R4638  Q_RES  243 1% CHIP  pkg 1206LF  page 260 : A = P5V ; B = VR_P5V_EN_D
R2487  Q_RES  4.7K 1% EMPTY  pkg 0402LF  page 155 : A = P3V3_AUX ; B = IRQ_LVC3_WAKE_BUF_N

(kicad_pcb
	(version 20260206)
	(generator "pcbnew")
	(generator_version "10.0")
	(general
		(thickness 1.6)
		(legacy_teardrops no)
	)
	(paper "A4")
	(title_block
		(title "03242023_DA0F0TMBIJ0_F0T_Motherboard_J_brd_V01_OCP.brd")
		(comment 1 "Grand Teton / footprints 1151-1153 of 6105")
	)
	(layers
		(0 "F.Cu" signal "TOP")
		(4 "In1.Cu" signal "GND")
		(6 "In2.Cu" signal "IN1")
		(8 "In3.Cu" signal "GND1")
		(10 "In4.Cu" signal "IN2")
		(12 "In5.Cu" signal "GND2")
		(14 "In6.Cu" signal "IN3")
		(16 "In7.Cu" signal "GND3")
		(18 "In8.Cu" signal "VCC")
		(20 "In9.Cu" signal "VCC1")
		(22 "In10.Cu" signal "GND4")
		(24 "In11.Cu" signal "IN4")
		(26 "In12.Cu" signal "GND5")
		(28 "In13.Cu" signal "IN5")
		(30 "In14.Cu" signal "GND6")
		(32 "In15.Cu" signal "IN6")
		(34 "In16.Cu" signal "GND7")
		(2 "B.Cu" signal "BOTTOM")
		(9 "F.Adhes" user "F.Adhesive")
		(11 "B.Adhes" user "B.Adhesive")
		(13 "F.Paste" user "Package Geometry/Pastemask Top")
		(15 "B.Paste" user "Package Geometry/Pastemask Bottom")
		(5 "F.SilkS" user "Ref Des/Silkscreen Top")
		(7 "B.SilkS" user "Ref Des/Silkscreen Bottom")
		(1 "F.Mask" user "Board Geometry/Soldermask Top")
		(3 "B.Mask" user "Board Geometry/Soldermask Bottom")
		(17 "Dwgs.User" user "User.Drawings")
		(19 "Cmts.User" user "User.Comments")
		(21 "Eco1.User" user "User.Eco1")
		(23 "Eco2.User" user "User.Eco2")
		(25 "Edge.Cuts" user "Board Geometry/Outline")
		(27 "Margin" user)
		(31 "F.CrtYd" user "Package Geometry/Place Bound Top")
		(29 "B.CrtYd" user "Package Geometry/Place Bound Bottom")
		(35 "F.Fab" user "Ref Des/Assembly Top")
		(33 "B.Fab" user "Ref Des/Assembly Bottom")
	)
	(footprint ""
		(layer "F.Cu")
		(at 306.263294 -14.51102)
		(property "Reference" "R2487"
			(at 0 0 0)
			(layer "F.SilkS")
			(hide yes)
			(effects
				(font
					(size 1.27 1.27)
				)
			)
		)
		(property "Value" ""
			(at 0 0 0)
			(layer "F.Fab")
			(effects
				(font
					(size 1.27 1.27)
				)
			)
		)
		(duplicate_pad_numbers_are_jumpers no)
		(fp_line
			(start -0.7874 -0.4064)
			(end 0.7874 -0.4064)
			(stroke
				(width 0.1524)
				(type default)
			)
			(layer "F.SilkS")
		)
		(fp_line
			(start -0.7874 0.4064)
			(end -0.7874 -0.4064)
			(stroke
				(width 0.1524)
				(type default)
			)
			(layer "F.SilkS")
		)
		(fp_line
			(start 0.7874 -0.4064)
			(end 0.7874 0.4064)
			(stroke
				(width 0.1524)
				(type default)
			)
			(layer "F.SilkS")
		)
		(fp_line
			(start 0.7874 0.4064)
			(end -0.7874 0.4064)
			(stroke
				(width 0.1524)
				(type default)
			)
			(layer "F.SilkS")
		)
		(fp_line
			(start -0.67945 -0.305054)
			(end -0.12065 -0.305054)
			(stroke
				(width 0.1)
				(type default)
			)
			(layer "F.Fab")
		)
		(fp_line
			(start -0.67945 0.3048)
			(end -0.67945 -0.305054)
			(stroke
				(width 0.1)
				(type default)
			)
			(layer "F.Fab")
		)
		(fp_line
			(start -0.12065 -0.305054)
			(end -0.12065 -0.2794)
			(stroke
				(width 0.1)
				(type default)
			)
			(layer "F.Fab")
		)
		(fp_line
			(start -0.12065 -0.2794)
			(end 0.12065 -0.2794)
			(stroke
				(width 0.1)
				(type default)
			)
			(layer "F.Fab")
		)
		(fp_line
			(start -0.12065 0.2794)
			(end -0.12065 0.3048)
			(stroke
				(width 0.1)
				(type default)
			)
			(layer "F.Fab")
		)
		(fp_line
			(start -0.12065 0.3048)
			(end -0.67945 0.3048)
			(stroke
				(width 0.1)
				(type default)
			)
			(layer "F.Fab")
		)
		(fp_line
			(start 0.120396 0.2794)
			(end -0.12065 0.2794)
			(stroke
				(width 0.1)
				(type default)
			)
			(layer "F.Fab")
		)
		(fp_line
			(start 0.120396 0.3048)
			(end 0.120396 0.2794)
			(stroke
				(width 0.1)
				(type default)
			)
			(layer "F.Fab")
		)
		(fp_line
			(start 0.12065 -0.3048)
			(end 0.67945 -0.3048)
			(stroke
				(width 0.1)
				(type default)
			)
			(layer "F.Fab")
		)
		(fp_line
			(start 0.12065 -0.2794)
			(end 0.12065 -0.3048)
			(stroke
				(width 0.1)
				(type default)
			)
			(layer "F.Fab")
		)
		(fp_line
			(start 0.67945 -0.3048)
			(end 0.67945 0.3048)
			(stroke
				(width 0.1)
				(type default)
			)
			(layer "F.Fab")
		)
		(fp_line
			(start 0.67945 0.3048)
			(end 0.120396 0.3048)
			(stroke
				(width 0.1)
				(type default)
			)
			(layer "F.Fab")
		)
		(pad "1" smd circle
			(at -0.40005 0)
			(size 0 0)
			(layers "F.Cu" "F.Mask" "F.Paste")
			(net "P3V3_AUX")
		)
		(pad "2" smd circle
			(at 0.40005 0)
			(size 0 0)
			(layers "F.Cu" "F.Mask" "F.Paste")
			(net "IRQ_LVC3_WAKE_BUF_N")
		)
	)
	(footprint ""
		(layer "F.Cu")
		(at 155.194 -126.365 -90)
		(property "Reference" "R4638"
			(at 0 0 270)
			(layer "F.SilkS")
			(hide yes)
			(effects
				(font
					(size 1.27 1.27)
				)
			)
		)
		(property "Value" ""
			(at 0 0 270)
			(layer "F.Fab")
			(effects
				(font
					(size 1.27 1.27)
				)
			)
		)
		(duplicate_pad_numbers_are_jumpers no)
		(fp_line
			(start -2.234946 0.9271)
			(end -2.234946 -0.9271)
			(stroke
				(width 0.1524)
				(type default)
			)
			(layer "F.SilkS")
		)
		(fp_line
			(start 2.234946 0.9271)
			(end -2.234946 0.9271)
			(stroke
				(width 0.1524)
				(type default)
			)
			(layer "F.SilkS")
		)
		(fp_line
			(start -2.234946 -0.9271)
			(end 2.234946 -0.9271)
			(stroke
				(width 0.1524)
				(type default)
			)
			(layer "F.SilkS")
		)
		(fp_line
			(start 2.234946 -0.9271)
			(end 2.234946 0.9271)
			(stroke
				(width 0.1524)
				(type default)
			)
			(layer "F.SilkS")
		)
		(fp_line
			(start -1.575054 0.824992)
			(end 1.575054 0.824992)
			(stroke
				(width 0.1)
				(type default)
			)
			(layer "F.Fab")
		)
		(fp_line
			(start 1.575054 0.824992)
			(end 1.575054 -0.824992)
			(stroke
				(width 0.1)
				(type default)
			)
			(layer "F.Fab")
		)
		(fp_line
			(start -1.575054 -0.824992)
			(end -1.575054 0.824992)
			(stroke
				(width 0.1)
				(type default)
			)
			(layer "F.Fab")
		)
		(fp_line
			(start 1.575054 -0.824992)
			(end -1.575054 -0.824992)
			(stroke
				(width 0.1)
				(type default)
			)
			(layer "F.Fab")
		)
		(pad "1" smd rect
			(at -1.599946 0 270)
			(size 1.016 1.6002)
			(layers "F.Cu" "F.Mask" "F.Paste")
			(net "P5V")
		)
		(pad "2" smd rect
			(at 1.599946 0 270)
			(size 1.016 1.6002)
			(layers "F.Cu" "F.Mask" "F.Paste")
			(net "VR_P5V_EN_D")
		)
	)
	(footprint ""
		(layer "F.Cu")
		(at 129.69748 -327.79335)
		(property "Reference" "PL27"
			(at 4.329684 4.104894 0)
			(unlocked yes)
			(layer "F.SilkS")
			(effects
				(font
					(size 0.7874 0.5842)
					(thickness 0.1524)
				)
				(justify left)
			)
		)
		(property "Value" ""
			(at 0 0 0)
			(layer "F.Fab")
			(effects
				(font
					(size 1.27 1.27)
				)
			)
		)
		(duplicate_pad_numbers_are_jumpers no)
		(fp_line
			(start -3.750056 -5.500116)
			(end -2.393442 -5.500116)
			(stroke
				(width 0.1524)
				(type default)
			)
			(layer "F.SilkS")
		)
		(fp_line
			(start -3.750056 5.500116)
			(end -3.750056 -5.500116)
			(stroke
				(width 0.1524)
				(type default)
			)
			(layer "F.SilkS")
		)
		(fp_line
			(start -2.393442 5.500116)
			(end -3.750056 5.500116)
			(stroke
				(width 0.1524)
				(type default)
			)
			(layer "F.SilkS")
		)
		(fp_line
			(start 2.393442 5.500116)
			(end 3.750056 5.500116)
			(stroke
				(width 0.1524)
				(type default)
			)
			(layer "F.SilkS")
		)
		(fp_line
			(start 3.750056 -5.500116)
			(end 2.393442 -5.500116)
			(stroke
				(width 0.1524)
				(type default)
			)
			(layer "F.SilkS")
		)
		(fp_line
			(start 3.750056 5.500116)
			(end 3.750056 -5.500116)
			(stroke
				(width 0.1524)
				(type default)
			)
			(layer "F.SilkS")
		)
		(fp_poly
			(pts
				(xy -5.12318 -4.930648) (xy -4.10718 -4.422648) (xy -5.12318 -3.914648)
			)
			(stroke
				(width 0)
				(type default)
			)
			(fill yes)
			(layer "F.SilkS")
		)
		(fp_line
			(start -3.750056 -5.500116)
			(end -3.750056 5.500116)
			(stroke
				(width 0.1)
				(type default)
			)
			(layer "F.Fab")
		)
		(fp_line
			(start -3.750056 5.500116)
			(end 3.750056 5.500116)
			(stroke
				(width 0.1)
				(type default)
			)
			(layer "F.Fab")
		)
		(fp_line
			(start 3.750056 -5.500116)
			(end -3.750056 -5.500116)
			(stroke
				(width 0.1)
				(type default)
			)
			(layer "F.Fab")
		)
		(fp_line
			(start 3.750056 5.500116)
			(end 3.750056 -5.500116)
			(stroke
				(width 0.1)
				(type default)
			)
			(layer "F.Fab")
		)
		(fp_poly
			(pts
				(xy -4.9276 -4.757928) (xy -4.9276 -3.741928) (xy -3.9116 -4.249928)
			)
			(stroke
				(width 0)
				(type default)
			)
			(fill yes)
			(layer "F.Fab")
		)
		(pad "1" smd rect
			(at 0 -4.249928 270)
			(size 2.413 4.5212)
			(layers "F.Cu" "F.Mask" "F.Paste")
			(net "SW_PVCCIN_CPU1_SW5")
		)
		(pad "2" smd rect
			(at 0 -1.175004 270)
			(size 1.3716 4.5212)
			(layers "F.Cu" "F.Mask" "F.Paste")
			(net "IND_P1_CPL5")
		)
		(pad "3" smd rect
			(at 0 1.175004 270)
			(size 1.3716 4.5212)
			(layers "F.Cu" "F.Mask" "F.Paste")
			(net "IND_P1_CPL4")
		)
		(pad "4" smd rect
			(at 0 4.249928 270)
			(size 2.413 4.5212)
			(layers "F.Cu" "F.Mask" "F.Paste")
			(net "PVCCIN_CPU1")
		)
	)
)
